(kicad_pcb
	(version 20260206)
	(generator "pcbnew")
	(generator_version "10.0")
	(general
		(thickness 1.6)
		(legacy_teardrops no)
	)
	(paper "A4")
	(title_block
		(title "baseboard — 13948-1b.1110WZS1818.brd")
		(comment 1 "Honey Badger (Wiwynn) / footprints 595-602 of 2523")
	)
	(layers
		(0 "F.Cu" signal "TOP")
		(4 "In1.Cu" signal "L2GND")
		(6 "In2.Cu" signal "L3")
		(8 "In3.Cu" signal "L4VCC")
		(10 "In4.Cu" signal "L5VCC")
		(12 "In5.Cu" signal "L6")
		(14 "In6.Cu" signal "L7GND")
		(2 "B.Cu" signal "BOTTOM")
		(9 "F.Adhes" user "F.Adhesive")
		(11 "B.Adhes" user "B.Adhesive")
		(13 "F.Paste" user "Package Geometry/Pastemask Top")
		(15 "B.Paste" user "Package Geometry/Pastemask Bottom")
		(5 "F.SilkS" user "Ref Des/Silkscreen Top")
		(7 "B.SilkS" user "Ref Des/Silkscreen Bottom")
		(1 "F.Mask" user "Board Geometry/Soldermask Top")
		(3 "B.Mask" user "Board Geometry/Soldermask Bottom")
		(17 "Dwgs.User" user "User.Drawings")
		(19 "Cmts.User" user "User.Comments")
		(21 "Eco1.User" user "User.Eco1")
		(23 "Eco2.User" user "User.Eco2")
		(25 "Edge.Cuts" user "Board Geometry/Outline")
		(27 "Margin" user)
		(31 "F.CrtYd" user "Package Geometry/Place Bound Top")
		(29 "B.CrtYd" user "Package Geometry/Place Bound Bottom")
		(35 "F.Fab" user "Ref Des/Assembly Top")
		(33 "B.Fab" user "Ref Des/Assembly Bottom")
	)
	(footprint ""
		(layer "F.Cu")
		(at 114.82197 -114.3 180)
		(property "Reference" "SC1075"
			(at 0 0 180)
			(layer "F.SilkS")
			(hide yes)
			(effects
				(font
					(size 1.27 1.27)
				)
			)
		)
		(property "Value" "SCD01U10V1KX-GP"
			(at -2.8321 -1.7399 180)
			(unlocked yes)
			(layer "F.Fab")
			(hide yes)
			(effects
				(font
					(size 1.016 1.016)
					(thickness 0.1524)
				)
			)
		)
		(property "Device Type" "C0201H13"
			(at -2.8321 -3.2639 180)
			(unlocked yes)
			(layer "F.Fab")
			(hide yes)
			(effects
				(font
					(size 1.016 1.016)
					(thickness 0.1524)
				)
			)
		)
		(duplicate_pad_numbers_are_jumpers no)
		(fp_rect
			(start -0.2794 0.6477)
			(end 0.2794 -0.6477)
			(stroke
				(width 0)
				(type default)
			)
			(fill no)
			(layer "F.CrtYd")
		)
		(fp_rect
			(start -0.2794 0.6477)
			(end 0.2794 -0.6477)
			(stroke
				(width 0)
				(type default)
			)
			(fill no)
			(layer "F.Fab")
		)
		(pad "1" smd custom
			(at 0 -0.2794 180)
			(size 0.0762 0.0762)
			(layers "F.Cu" "F.Mask" "F.Paste")
			(net "SAS_HDD_TX4_P")
			(options
				(clearance outline)
				(anchor circle)
			)
			(primitives
				(gr_poly
					(pts
						(arc
							(start 0.1524 -0.127)
							(mid 0.137521 -0.162921)
							(end 0.1016 -0.1778)
						)
						(arc
							(start -0.1016 -0.1778)
							(mid -0.137521 -0.162921)
							(end -0.1524 -0.127)
						)
						(arc
							(start -0.1524 0.127)
							(mid -0.137521 0.162921)
							(end -0.1016 0.1778)
						)
						(arc
							(start 0.1016 0.1778)
							(mid 0.137521 0.162921)
							(end 0.1524 0.127)
						)
					)
					(width 0)
					(fill yes)
				)
			)
		)
		(pad "2" smd custom
			(at 0 0.2794 180)
			(size 0.0762 0.0762)
			(layers "F.Cu" "F.Mask" "F.Paste")
			(net "SAS_HDD_REDV_TX8_P")
			(options
				(clearance outline)
				(anchor circle)
			)
			(primitives
				(gr_poly
					(pts
						(arc
							(start 0.1524 -0.127)
							(mid 0.137521 -0.162921)
							(end 0.1016 -0.1778)
						)
						(arc
							(start -0.1016 -0.1778)
							(mid -0.137521 -0.162921)
							(end -0.1524 -0.127)
						)
						(arc
							(start -0.1524 0.127)
							(mid -0.137521 0.162921)
							(end -0.1016 0.1778)
						)
						(arc
							(start 0.1016 0.1778)
							(mid 0.137521 0.162921)
							(end 0.1524 0.127)
						)
					)
					(width 0)
					(fill yes)
				)
			)
		)
	)
	(footprint ""
		(layer "F.Cu")
		(at 302.768 -191.897)
		(property "Reference" "R173"
			(at 0 0 0)
			(layer "F.SilkS")
			(hide yes)
			(effects
				(font
					(size 1.27 1.27)
				)
			)
		)
		(property "Value" "4K7R2F-GP"
			(at 0.064008 -3.993896 0)
			(unlocked yes)
			(layer "F.Fab")
			(hide yes)
			(effects
				(font
					(size 1.016 1.016)
					(thickness 0.1524)
				)
			)
		)
		(property "Device Type" "R402H16"
			(at 0.064008 -5.517896 0)
			(unlocked yes)
			(layer "F.Fab")
			(hide yes)
			(effects
				(font
					(size 1.016 1.016)
					(thickness 0.1524)
				)
			)
		)
		(duplicate_pad_numbers_are_jumpers no)
		(fp_line
			(start -0.508 -0.9398)
			(end -0.508 0.9398)
			(stroke
				(width 0.1524)
				(type default)
			)
			(layer "F.SilkS")
		)
		(fp_line
			(start 0.508 -0.9398)
			(end -0.508 -0.9398)
			(stroke
				(width 0.1524)
				(type default)
			)
			(layer "F.SilkS")
		)
		(fp_rect
			(start -0.508 0.9398)
			(end 0.508 -0.9398)
			(stroke
				(width 0)
				(type default)
			)
			(fill no)
			(layer "F.CrtYd")
		)
		(fp_rect
			(start -0.508 0.9398)
			(end 0.508 -0.9398)
			(stroke
				(width 0)
				(type default)
			)
			(fill no)
			(layer "F.Fab")
		)
		(pad "1" smd custom
			(at 0 -0.4445)
			(size 0.1397 0.1397)
			(layers "F.Cu" "F.Mask" "F.Paste")
			(net "P3V3_STBY")
			(options
				(clearance outline)
				(anchor circle)
			)
			(primitives
				(gr_poly
					(pts
						(arc
							(start -0.1778 -0.2794)
							(mid -0.249642 -0.249642)
							(end -0.2794 -0.1778)
						)
						(arc
							(start -0.2794 0.1778)
							(mid -0.249642 0.249642)
							(end -0.1778 0.2794)
						)
						(arc
							(start 0.1778 0.2794)
							(mid 0.249642 0.249642)
							(end 0.2794 0.1778)
						)
						(arc
							(start 0.2794 -0.1778)
							(mid 0.249642 -0.249642)
							(end 0.1778 -0.2794)
						)
					)
					(width 0)
					(fill yes)
				)
			)
		)
		(pad "2" smd custom
			(at 0 0.4445)
			(size 0.1397 0.1397)
			(layers "F.Cu" "F.Mask" "F.Paste")
			(net "UART COUNT")
			(options
				(clearance outline)
				(anchor circle)
			)
			(primitives
				(gr_poly
					(pts
						(arc
							(start -0.1778 -0.2794)
							(mid -0.249642 -0.249642)
							(end -0.2794 -0.1778)
						)
						(arc
							(start -0.2794 0.1778)
							(mid -0.249642 0.249642)
							(end -0.1778 0.2794)
						)
						(arc
							(start 0.1778 0.2794)
							(mid 0.249642 0.249642)
							(end 0.2794 0.1778)
						)
						(arc
							(start 0.2794 -0.1778)
							(mid 0.249642 -0.249642)
							(end 0.1778 -0.2794)
						)
					)
					(width 0)
					(fill yes)
				)
			)
		)
	)
	(footprint ""
		(layer "F.Cu")
		(at 109.48797 -114.3 180)
		(property "Reference" "SC1081"
			(at 0 0 180)
			(layer "F.SilkS")
			(hide yes)
			(effects
				(font
					(size 1.27 1.27)
				)
			)
		)
		(property "Value" "SCD01U10V1KX-GP"
			(at -2.8321 -1.7399 180)
			(unlocked yes)
			(layer "F.Fab")
			(hide yes)
			(effects
				(font
					(size 1.016 1.016)
					(thickness 0.1524)
				)
			)
		)
		(property "Device Type" "C0201H13"
			(at -2.8321 -3.2639 180)
			(unlocked yes)
			(layer "F.Fab")
			(hide yes)
			(effects
				(font
					(size 1.016 1.016)
					(thickness 0.1524)
				)
			)
		)
		(duplicate_pad_numbers_are_jumpers no)
		(fp_rect
			(start -0.2794 0.6477)
			(end 0.2794 -0.6477)
			(stroke
				(width 0)
				(type default)
			)
			(fill no)
			(layer "F.CrtYd")
		)
		(fp_rect
			(start -0.2794 0.6477)
			(end 0.2794 -0.6477)
			(stroke
				(width 0)
				(type default)
			)
			(fill no)
			(layer "F.Fab")
		)
		(pad "1" smd custom
			(at 0 -0.2794 180)
			(size 0.0762 0.0762)
			(layers "F.Cu" "F.Mask" "F.Paste")
			(net "SAS_HDD_TX7_P")
			(options
				(clearance outline)
				(anchor circle)
			)
			(primitives
				(gr_poly
					(pts
						(arc
							(start 0.1524 -0.127)
							(mid 0.137521 -0.162921)
							(end 0.1016 -0.1778)
						)
						(arc
							(start -0.1016 -0.1778)
							(mid -0.137521 -0.162921)
							(end -0.1524 -0.127)
						)
						(arc
							(start -0.1524 0.127)
							(mid -0.137521 0.162921)
							(end -0.1016 0.1778)
						)
						(arc
							(start 0.1016 0.1778)
							(mid 0.137521 0.162921)
							(end 0.1524 0.127)
						)
					)
					(width 0)
					(fill yes)
				)
			)
		)
		(pad "2" smd custom
			(at 0 0.2794 180)
			(size 0.0762 0.0762)
			(layers "F.Cu" "F.Mask" "F.Paste")
			(net "SAS_EXP_GF_TX_DP11")
			(options
				(clearance outline)
				(anchor circle)
			)
			(primitives
				(gr_poly
					(pts
						(arc
							(start 0.1524 -0.127)
							(mid 0.137521 -0.162921)
							(end 0.1016 -0.1778)
						)
						(arc
							(start -0.1016 -0.1778)
							(mid -0.137521 -0.162921)
							(end -0.1524 -0.127)
						)
						(arc
							(start -0.1524 0.127)
							(mid -0.137521 0.162921)
							(end -0.1016 0.1778)
						)
						(arc
							(start 0.1016 0.1778)
							(mid 0.137521 0.162921)
							(end 0.1524 0.127)
						)
					)
					(width 0)
					(fill yes)
				)
			)
		)
	)
	(footprint ""
		(layer "F.Cu")
		(at 87.757 -224.663 -90)
		(property "Reference" "SR783"
			(at 0 0 270)
			(layer "F.SilkS")
			(hide yes)
			(effects
				(font
					(size 1.27 1.27)
				)
			)
		)
		(property "Value" "4K7R2F-GP"
			(at 0.064008 -3.993896 270)
			(unlocked yes)
			(layer "F.Fab")
			(hide yes)
			(effects
				(font
					(size 1.016 1.016)
					(thickness 0.1524)
				)
			)
		)
		(property "Device Type" "R402H16"
			(at 0.064008 -5.517896 270)
			(unlocked yes)
			(layer "F.Fab")
			(hide yes)
			(effects
				(font
					(size 1.016 1.016)
					(thickness 0.1524)
				)
			)
		)
		(duplicate_pad_numbers_are_jumpers no)
		(fp_line
			(start -0.508 -0.9398)
			(end -0.508 0.9398)
			(stroke
				(width 0.1524)
				(type default)
			)
			(layer "F.SilkS")
		)
		(fp_line
			(start 0.508 -0.9398)
			(end -0.508 -0.9398)
			(stroke
				(width 0.1524)
				(type default)
			)
			(layer "F.SilkS")
		)
		(fp_rect
			(start -0.508 0.9398)
			(end 0.508 -0.9398)
			(stroke
				(width 0)
				(type default)
			)
			(fill no)
			(layer "F.CrtYd")
		)
		(fp_rect
			(start -0.508 0.9398)
			(end 0.508 -0.9398)
			(stroke
				(width 0)
				(type default)
			)
			(fill no)
			(layer "F.Fab")
		)
		(pad "1" smd custom
			(at 0 -0.4445 270)
			(size 0.1397 0.1397)
			(layers "F.Cu" "F.Mask" "F.Paste")
			(net "EXP_SCL_L_0")
			(options
				(clearance outline)
				(anchor circle)
			)
			(primitives
				(gr_poly
					(pts
						(arc
							(start -0.1778 -0.2794)
							(mid -0.249642 -0.249642)
							(end -0.2794 -0.1778)
						)
						(arc
							(start -0.2794 0.1778)
							(mid -0.249642 0.249642)
							(end -0.1778 0.2794)
						)
						(arc
							(start 0.1778 0.2794)
							(mid 0.249642 0.249642)
							(end 0.2794 0.1778)
						)
						(arc
							(start 0.2794 -0.1778)
							(mid 0.249642 -0.249642)
							(end 0.1778 -0.2794)
						)
					)
					(width 0)
					(fill yes)
				)
			)
		)
		(pad "2" smd custom
			(at 0 0.4445 270)
			(size 0.1397 0.1397)
			(layers "F.Cu" "F.Mask" "F.Paste")
			(net "P3V3_STBY")
			(options
				(clearance outline)
				(anchor circle)
			)
			(primitives
				(gr_poly
					(pts
						(arc
							(start -0.1778 -0.2794)
							(mid -0.249642 -0.249642)
							(end -0.2794 -0.1778)
						)
						(arc
							(start -0.2794 0.1778)
							(mid -0.249642 0.249642)
							(end -0.1778 0.2794)
						)
						(arc
							(start 0.1778 0.2794)
							(mid 0.249642 0.249642)
							(end 0.2794 0.1778)
						)
						(arc
							(start 0.2794 -0.1778)
							(mid 0.249642 -0.249642)
							(end 0.1778 -0.2794)
						)
					)
					(width 0)
					(fill yes)
				)
			)
		)
	)
	(footprint ""
		(layer "F.Cu")
		(at 275.082 -44.958)
		(property "Reference" "PL4"
			(at 0 0 0)
			(layer "F.SilkS")
			(hide yes)
			(effects
				(font
					(size 1.27 1.27)
				)
			)
		)
		(property "Value" "BLM21PG220SN1DGP"
			(at 0.0254 -5.6896 0)
			(unlocked yes)
			(layer "F.Fab")
			(hide yes)
			(effects
				(font
					(size 1.016 1.016)
					(thickness 0.1524)
				)
			)
		)
		(property "Device Type" "L20125H42"
			(at 0.0254 -7.5946 0)
			(unlocked yes)
			(layer "F.Fab")
			(hide yes)
			(effects
				(font
					(size 1.016 1.016)
					(thickness 0.1524)
				)
			)
		)
		(duplicate_pad_numbers_are_jumpers no)
		(fp_line
			(start -0.9144 -1.7018)
			(end -0.9144 1.7018)
			(stroke
				(width 0.1524)
				(type default)
			)
			(layer "F.SilkS")
		)
		(fp_line
			(start -0.9144 1.7018)
			(end 0.9144 1.7018)
			(stroke
				(width 0.1524)
				(type default)
			)
			(layer "F.SilkS")
		)
		(fp_line
			(start 0.9144 -1.7018)
			(end -0.9144 -1.7018)
			(stroke
				(width 0.1524)
				(type default)
			)
			(layer "F.SilkS")
		)
		(fp_line
			(start 0.9144 1.7018)
			(end 0.9144 -1.7018)
			(stroke
				(width 0.1524)
				(type default)
			)
			(layer "F.SilkS")
		)
		(fp_rect
			(start -1.0033 1.778)
			(end 1.0033 -1.778)
			(stroke
				(width 0)
				(type default)
			)
			(fill no)
			(layer "F.CrtYd")
		)
		(fp_poly
			(pts
				(xy -1.0033 -1.778) (xy 1.0033 -1.778) (xy 1.0033 1.778) (xy -1.0033 1.778)
			)
			(stroke
				(width 0)
				(type default)
			)
			(fill no)
			(layer "F.Fab")
		)
		(pad "1" smd rect
			(at 0 -0.9652)
			(size 1.397 1.143)
			(layers "F.Cu" "F.Mask" "F.Paste")
			(net "P12V")
		)
		(pad "2" smd rect
			(at 0 0.9652)
			(size 1.397 1.143)
			(layers "F.Cu" "F.Mask" "F.Paste")
			(net "P1V8_STBY_VIN")
		)
	)
	(footprint ""
		(layer "F.Cu")
		(at 88.2904 -3.683)
		(property "Reference" "PC196"
			(at 0 0 0)
			(layer "F.SilkS")
			(hide yes)
			(effects
				(font
					(size 1.27 1.27)
				)
			)
		)
		(property "Value" "SC22U6D3V6KX-2-GP"
			(at -0.0762 -5.1308 0)
			(unlocked yes)
			(layer "F.Fab")
			(hide yes)
			(effects
				(font
					(size 1.016 1.016)
					(thickness 0.1524)
				)
			)
		)
		(property "Device Type" "C1206H71"
			(at -0.127 -6.6548 0)
			(unlocked yes)
			(layer "F.Fab")
			(hide yes)
			(effects
				(font
					(size 1.016 1.016)
					(thickness 0.1524)
				)
			)
		)
		(duplicate_pad_numbers_are_jumpers no)
		(fp_line
			(start -1.016 -2.2352)
			(end 1.016 -2.2352)
			(stroke
				(width 0.1524)
				(type default)
			)
			(layer "F.SilkS")
		)
		(fp_line
			(start -1.016 -0.8382)
			(end -1.016 -2.2352)
			(stroke
				(width 0.1524)
				(type default)
			)
			(layer "F.SilkS")
		)
		(fp_line
			(start -1.016 2.2352)
			(end -1.016 0.8382)
			(stroke
				(width 0.1524)
				(type default)
			)
			(layer "F.SilkS")
		)
		(fp_line
			(start 1.016 -2.2352)
			(end 1.016 -0.8382)
			(stroke
				(width 0.1524)
				(type default)
			)
			(layer "F.SilkS")
		)
		(fp_line
			(start 1.016 0.8382)
			(end 1.016 2.2352)
			(stroke
				(width 0.1524)
				(type default)
			)
			(layer "F.SilkS")
		)
		(fp_line
			(start 1.016 2.2352)
			(end -1.016 2.2352)
			(stroke
				(width 0.1524)
				(type default)
			)
			(layer "F.SilkS")
		)
		(fp_rect
			(start -1.0922 2.3114)
			(end 1.0922 -2.3114)
			(stroke
				(width 0)
				(type default)
			)
			(fill no)
			(layer "F.CrtYd")
		)
		(fp_poly
			(pts
				(xy 1.0922 -2.3114) (xy 1.0922 2.3114) (xy -1.0922 2.3114) (xy -1.0922 -2.3114)
			)
			(stroke
				(width 0)
				(type default)
			)
			(fill no)
			(layer "F.Fab")
		)
		(pad "1" smd rect
			(at 0 -1.397)
			(size 1.651 1.27)
			(layers "F.Cu" "F.Mask" "F.Paste")
			(net "P0V955_C")
		)
		(pad "2" smd rect
			(at 0 1.397)
			(size 1.651 1.27)
			(layers "F.Cu" "F.Mask" "F.Paste")
			(net "GND")
		)
	)
	(footprint ""
		(layer "F.Cu")
		(at 194.760596 -112.033812 -90)
		(property "Reference" "PC231"
			(at 0 0 270)
			(layer "F.SilkS")
			(hide yes)
			(effects
				(font
					(size 1.27 1.27)
				)
			)
		)
		(property "Value" "SC2K2P50V3KX-GP"
			(at 0 -2.8194 270)
			(unlocked yes)
			(layer "F.Fab")
			(hide yes)
			(effects
				(font
					(size 1.016 1.016)
					(thickness 0.1524)
				)
			)
		)
		(property "Device Type" "C603"
			(at 0 -4.3434 270)
			(unlocked yes)
			(layer "F.Fab")
			(hide yes)
			(effects
				(font
					(size 1.016 1.016)
					(thickness 0.1524)
				)
			)
		)
		(duplicate_pad_numbers_are_jumpers no)
		(fp_line
			(start 0.508 0)
			(end -0.508 0)
			(stroke
				(width 0.2032)
				(type default)
			)
			(layer "F.SilkS")
		)
		(fp_rect
			(start -0.5842 1.3335)
			(end 0.5842 -1.3335)
			(stroke
				(width 0)
				(type default)
			)
			(fill no)
			(layer "F.CrtYd")
		)
		(fp_rect
			(start -0.5842 1.3335)
			(end 0.5842 -1.3335)
			(stroke
				(width 0)
				(type default)
			)
			(fill no)
			(layer "F.Fab")
		)
		(pad "1" smd custom
			(at 0 -0.762 270)
			(size 0.2159 0.2159)
			(layers "F.Cu" "F.Mask" "F.Paste")
			(net "P1V5_E_SW")
			(options
				(clearance outline)
				(anchor circle)
			)
			(primitives
				(gr_poly
					(pts
						(arc
							(start -0.3302 -0.4318)
							(mid -0.402042 -0.402042)
							(end -0.4318 -0.3302)
						)
						(arc
							(start -0.4318 0.3302)
							(mid -0.402042 0.402042)
							(end -0.3302 0.4318)
						)
						(arc
							(start 0.3302 0.4318)
							(mid 0.402042 0.402042)
							(end 0.4318 0.3302)
						)
						(arc
							(start 0.4318 -0.3302)
							(mid 0.402042 -0.402042)
							(end 0.3302 -0.4318)
						)
					)
					(width 0)
					(fill yes)
				)
			)
		)
		(pad "2" smd custom
			(at 0 0.762 270)
			(size 0.2159 0.2159)
			(layers "F.Cu" "F.Mask" "F.Paste")
			(net "P1V5_E_SNB")
			(options
				(clearance outline)
				(anchor circle)
			)
			(primitives
				(gr_poly
					(pts
						(arc
							(start -0.3302 -0.4318)
							(mid -0.402042 -0.402042)
							(end -0.4318 -0.3302)
						)
						(arc
							(start -0.4318 0.3302)
							(mid -0.402042 0.402042)
							(end -0.3302 0.4318)
						)
						(arc
							(start 0.3302 0.4318)
							(mid 0.402042 0.402042)
							(end 0.4318 0.3302)
						)
						(arc
							(start 0.4318 -0.3302)
							(mid 0.402042 -0.402042)
							(end 0.3302 -0.4318)
						)
					)
					(width 0)
					(fill yes)
				)
			)
		)
	)
	(footprint ""
		(layer "F.Cu")
		(at 226.568 -21.463 -90)
		(property "Reference" "R5774"
			(at 0 0 270)
			(layer "F.SilkS")
			(hide yes)
			(effects
				(font
					(size 1.27 1.27)
				)
			)
		)
		(property "Value" "330R1210J-GP"
			(at 0.0889 -6.9977 270)
			(unlocked yes)
			(layer "F.Fab")
			(hide yes)
			(effects
				(font
					(size 1.016 1.016)
					(thickness 0.1524)
				)
			)
		)
		(property "Device Type" "R1210H24"
			(at 0.0635 -8.636 270)
			(unlocked yes)
			(layer "F.Fab")
			(hide yes)
			(effects
				(font
					(size 1.016 1.016)
					(thickness 0.1524)
				)
			)
		)
		(duplicate_pad_numbers_are_jumpers no)
		(fp_line
			(start -1.651 2.413)
			(end -1.651 -2.413)
			(stroke
				(width 0.1524)
				(type default)
			)
			(layer "F.SilkS")
		)
		(fp_line
			(start 1.651 2.413)
			(end -1.651 2.413)
			(stroke
				(width 0.1524)
				(type default)
			)
			(layer "F.SilkS")
		)
		(fp_line
			(start -1.651 -2.413)
			(end 1.651 -2.413)
			(stroke
				(width 0.1524)
				(type default)
			)
			(layer "F.SilkS")
		)
		(fp_line
			(start 1.651 -2.413)
			(end 1.651 2.413)
			(stroke
				(width 0.1524)
				(type default)
			)
			(layer "F.SilkS")
		)
		(fp_poly
			(pts
				(xy -1.651 -2.413) (xy 1.651 -2.413) (xy 1.651 2.413) (xy -1.651 2.413)
			)
			(stroke
				(width 0)
				(type default)
			)
			(fill no)
			(layer "F.CrtYd")
		)
		(fp_poly
			(pts
				(xy -1.651 -2.413) (xy 1.651 -2.413) (xy 1.651 2.413) (xy -1.651 2.413)
			)
			(stroke
				(width 0)
				(type default)
			)
			(fill no)
			(layer "F.Fab")
		)
		(pad "1" smd rect
			(at 0 -1.4732 270)
			(size 2.794 1.397)
			(layers "F.Cu" "F.Mask" "F.Paste")
			(net "P5V_STBY")
		)
		(pad "2" smd rect
			(at 0 1.4732 270)
			(size 2.794 1.397)
			(layers "F.Cu" "F.Mask" "F.Paste")
			(net "LED_PWR_N_R")
		)
	)
)
